FILE_TYPE = MACRO_DRAWING;
SET COLOR_WIRE YELLOW;
SET COLOR_PROP ORANGE;
SET COLOR_DOT WHITE;
SET COLOR_ARC YELLOW;
SET COLOR_BODY GREEN;
SET COLOR_NOTE PURPLE;
SET PROP_DISPLAY VALUE;
SET PAGE_NUMBER P9;
SET PATH_NUMBER P0;
FORCEADD QUANTA_TITLE_BLOCK_C..1
(5050 -1325);
FORCEPROP 0 LAST CDS_CON_LAST_MODIFIED Fri Aug 25 17:25:35 2023
J 0
(3165 -1310);
DISPLAY INVISIBLE (3165 -1310);
FORCEPROP 2 LAST Q_DEPT 
J 1
(1287 -1276);
DISPLAY 1.957447 (1287 -1276);
PAINT GREEN (1287 -1276);
FORCEPROP 1 LAST CUSTOM_TXT_CDS <CON_LAST_MODIFIED>
J 0
(3165 -1310);
DISPLAY 0.978723 (3165 -1310);
FORCEPROP 2 LAST CUSTOM_TXT_CDS <XR_PAGE_TITLE>
J 0
(-2840 3925);
DISPLAY 0.638298 (-2840 3925);
PAINT PINK (-2840 3925);
DISPLAY INVISIBLE (-2840 3925);
FORCEPROP 1 LAST CUSTOM_TXT_CDS <NAME_2>
J 0
(1875 -1275);
FORCEPROP 1 LAST CUSTOM_TXT_CDS <NAME_1>
J 0
(1875 -1150);
FORCEPROP 1 LAST CUSTOM_TXT_CDS <Q_NUMBER>
J 0
(3647 -1222);
DISPLAY 1.212766 (3647 -1222);
FORCEPROP 1 LAST CUSTOM_TXT_CDS <Q_PROJ>
J 0
(2668 -1223);
DISPLAY 1.212766 (2668 -1223);
FORCEPROP 1 LAST CUSTOM_TXT_CDS <Q_REV>
J 0
(4866 -1222);
DISPLAY 1.212766 (4866 -1222);
FORCEPROP 1 LAST CUSTOM_TXT_CDS <CON_PAGE_NUM> OF <CON_TOTAL_PAGES>
J 0
(4604 -1307);
DISPLAY 0.978723 (4604 -1307);
FORCEPROP 1 LAST Q_TITLE POWER SEQUENCE TIMING
J 0
(-4316 -1299);
DISPLAY 2.446809 (-4316 -1299);
PAINT GREEN (-4316 -1299);
FORCEPROP 2 LAST PAGE_BORDER TRUE
J 0
(-2840 3925);
DISPLAY 0.638298 (-2840 3925);
PAINT PINK (-2840 3925);
DISPLAY INVISIBLE (-2840 3925);
FORCEPROP 1 LAST CDS_LMAN_SYM_OUTLINE -9475,6775,100,-125
J 0
(5050 -1325);
DISPLAY 0.468085 (5050 -1325);
PAINT GREEN (5050 -1325);
DISPLAY INVISIBLE (5050 -1325);
FORCEPROP 2 LAST CDS_LIB pure_quanta
J 0
(5050 -1325);
DISPLAY INVISIBLE (5050 -1325);
FORCEPROP 1 LAST COMMENT_BODY TRUE
J 0
(5062 -1338);
DISPLAY 0.978723 (5062 -1338);
PAINT PEACH (5062 -1338);
DISPLAY INVISIBLE (5062 -1338);
FORCEPROP 2 LAST CDS_XR_PAGE_TITLE CR-9 : @SCM_LIB.SCM(SCH_1):PAGE9
J 0
(-2840 3925);
DISPLAY 0.638298 (-2840 3925);
PAINT PINK (-2840 3925);
DISPLAY INVISIBLE (-2840 3925);
FORCENOTE
$CDS_IMAGE|timing_01.JPG|4250|3500
(2875 750) 0;
DISPLAY LEFT (2875 750);
FORCENOTE
$CDS_IMAGE|timing.JPG|5042|4500
(-1775 3100) 0;
DISPLAY LEFT (-1775 3100);
QUIT
